(kicad_pcb
	(version 20241229)
	(generator "pcbnew")
	(generator_version "9.0")
	(general
		(thickness 1.599998)
		(legacy_teardrops no)
	)
	(paper "A4")
	(title_block
		(title "Artix - Datacenter Secure Control Module (DC-SCM)")
		(date "2024-11-06")
		(rev "1.1.3")
		(comment 9 "footprints 5-9 of 544")
	)
	(layers
		(0 "F.Cu" signal)
		(4 "In1.Cu" signal)
		(6 "In2.Cu" signal)
		(8 "In3.Cu" signal)
		(10 "In4.Cu" signal)
		(12 "In5.Cu" signal)
		(14 "In6.Cu" signal)
		(2 "B.Cu" signal)
		(9 "F.Adhes" user "F.Adhesive")
		(11 "B.Adhes" user "B.Adhesive")
		(13 "F.Paste" user)
		(15 "B.Paste" user)
		(5 "F.SilkS" user "F.Silkscreen")
		(7 "B.SilkS" user "B.Silkscreen")
		(1 "F.Mask" user)
		(3 "B.Mask" user)
		(17 "Dwgs.User" user "User.Drawings")
		(19 "Cmts.User" user "User.Comments")
		(21 "Eco1.User" user "User.Eco1")
		(23 "Eco2.User" user "User.Eco2")
		(25 "Edge.Cuts" user)
		(27 "Margin" user)
		(31 "F.CrtYd" user "F.Courtyard")
		(29 "B.CrtYd" user "B.Courtyard")
		(35 "F.Fab" user)
		(33 "B.Fab" user)
	)
	(footprint "antmicro-footprints:C_0402_1005Metric"
		(layer "F.Cu")
		(at 131.275 154.375 -90)
		(descr "Capacitor SMD 0402")
		(tags "capacitor SMD 0402")
		(property "Reference" "C34"
			(at -2.98 -0.33 90)
			(layer "F.SilkS")
			(effects
				(font
					(size 0.7 0.7)
					(thickness 0.15)
				)
				(justify right bottom)
			)
		)
		(property "Value" "C_10u_0402"
			(at 0 1.4 90)
			(layer "F.Fab")
			(effects
				(font
					(size 0.7 0.7)
					(thickness 0.15)
				)
				(justify right bottom)
			)
		)
		(property "Datasheet" "https://www.yageo.com/en/Chart/Download/pdf/CC0402MRX5R5BB106"
			(at 0 0 270)
			(layer "F.Fab")
			(hide yes)
			(effects
				(font
					(size 1.27 1.27)
					(thickness 0.15)
				)
			)
		)
		(property "Description" "SMD Multilayer Ceramic Capacitor, 10 µF, 6.3 V, 0402 [1005 Metric], ± 20%, X5R, CC Series"
			(at 0 0 270)
			(layer "F.Fab")
			(hide yes)
			(effects
				(font
					(size 1.27 1.27)
					(thickness 0.15)
				)
			)
		)
		(property "Author" "Antmicro"
			(at -23.1 285.65 0)
			(layer "F.Fab")
			(hide yes)
			(effects
				(font
					(size 1 1)
					(thickness 0.15)
				)
			)
		)
		(property "Dielectric" ""
			(at -23.1 285.65 0)
			(layer "F.Fab")
			(hide yes)
			(effects
				(font
					(size 1 1)
					(thickness 0.15)
				)
			)
		)
		(property "License" "Apache-2.0"
			(at -23.1 285.65 0)
			(layer "F.Fab")
			(hide yes)
			(effects
				(font
					(size 1 1)
					(thickness 0.15)
				)
			)
		)
		(property "MPN" "CC0402MRX5R5BB106"
			(at -23.1 285.65 0)
			(layer "F.Fab")
			(hide yes)
			(effects
				(font
					(size 1 1)
					(thickness 0.15)
				)
			)
		)
		(property "Manufacturer" "YAGEO"
			(at -23.1 285.65 0)
			(layer "F.Fab")
			(hide yes)
			(effects
				(font
					(size 1 1)
					(thickness 0.15)
				)
			)
		)
		(property "Val" "10u"
			(at -23.1 285.65 0)
			(layer "F.Fab")
			(hide yes)
			(effects
				(font
					(size 1 1)
					(thickness 0.15)
				)
			)
		)
		(property "Voltage" ""
			(at -23.1 285.65 0)
			(layer "F.Fab")
			(hide yes)
			(effects
				(font
					(size 1 1)
					(thickness 0.15)
				)
			)
		)
		(sheetname "/PCIe-connector/")
		(sheetfile "pcie-conn.kicad_sch")
		(attr smd)
		(fp_rect
			(start -0.925 -0.47)
			(end 0.925 0.47)
			(stroke
				(width 0.05)
				(type default)
			)
			(fill no)
			(layer "F.CrtYd")
		)
		(fp_line
			(start -0.494 0.248)
			(end -0.494 -0.25)
			(stroke
				(width 0.15)
				(type solid)
			)
			(layer "F.Fab")
		)
		(fp_line
			(start 0.504 0.248)
			(end -0.494 0.248)
			(stroke
				(width 0.15)
				(type solid)
			)
			(layer "F.Fab")
		)
		(fp_line
			(start -0.494 -0.25)
			(end 0.504 -0.25)
			(stroke
				(width 0.15)
				(type solid)
			)
			(layer "F.Fab")
		)
		(fp_line
			(start 0.504 -0.25)
			(end 0.504 0.248)
			(stroke
				(width 0.15)
				(type solid)
			)
			(layer "F.Fab")
		)
		(pad "1" smd roundrect
			(at -0.48 0 270)
			(size 0.59 0.64)
			(layers "F.Cu" "F.Mask" "F.Paste")
			(roundrect_rratio 0.25)
			(net 1 "GND")
			(pintype "passive")
		)
		(pad "2" smd roundrect
			(at 0.48 0 270)
			(size 0.59 0.64)
			(layers "F.Cu" "F.Mask" "F.Paste")
			(roundrect_rratio 0.25)
			(net 2 "VCC3V3")
			(pintype "passive")
		)
	)
	(footprint "antmicro-footprints:C_0402_1005Metric"
		(layer "F.Cu")
		(at 125.995 168.181 -90)
		(descr "Capacitor SMD 0402")
		(tags "capacitor SMD 0402")
		(property "Reference" "C28"
			(at 0.819 -0.404 90)
			(layer "F.SilkS")
			(effects
				(font
					(size 0.7 0.7)
					(thickness 0.15)
				)
				(justify right bottom)
			)
		)
		(property "Value" "C_100n_6V3_0402"
			(at 0 1.4 90)
			(layer "F.Fab")
			(effects
				(font
					(size 0.7 0.7)
					(thickness 0.15)
				)
				(justify right bottom)
			)
		)
		(property "Datasheet" "https://www.passivecomponent.com/wp-content/uploads/datasheet/WTC_MLCC_General_Purpose.pdf"
			(at 0 0 270)
			(layer "F.Fab")
			(hide yes)
			(effects
				(font
					(size 1.27 1.27)
					(thickness 0.15)
				)
			)
		)
		(property "Description" "SMT Multilayer Ceramic Capacitor, 0.1 µF, 6.3 V, 0402 [1005 Metric], ± 10%, X5R, Walsin MLCC"
			(at 0 0 270)
			(layer "F.Fab")
			(hide yes)
			(effects
				(font
					(size 1.27 1.27)
					(thickness 0.15)
				)
			)
		)
		(property "Author" "Antmicro"
			(at -42.186 294.176 0)
			(layer "F.Fab")
			(hide yes)
			(effects
				(font
					(size 1 1)
					(thickness 0.15)
				)
			)
		)
		(property "Dielectric" ""
			(at -42.186 294.176 0)
			(layer "F.Fab")
			(hide yes)
			(effects
				(font
					(size 1 1)
					(thickness 0.15)
				)
			)
		)
		(property "License" "Apache-2.0"
			(at -42.186 294.176 0)
			(layer "F.Fab")
			(hide yes)
			(effects
				(font
					(size 1 1)
					(thickness 0.15)
				)
			)
		)
		(property "MPN" "0402X104K6R3CT"
			(at -42.186 294.176 0)
			(layer "F.Fab")
			(hide yes)
			(effects
				(font
					(size 1 1)
					(thickness 0.15)
				)
			)
		)
		(property "Manufacturer" "Walsin"
			(at -42.186 294.176 0)
			(layer "F.Fab")
			(hide yes)
			(effects
				(font
					(size 1 1)
					(thickness 0.15)
				)
			)
		)
		(property "Public" "False"
			(at -42.186 294.176 0)
			(layer "F.Fab")
			(hide yes)
			(effects
				(font
					(size 1 1)
					(thickness 0.15)
				)
			)
		)
		(property "Val" "100n"
			(at -42.186 294.176 0)
			(layer "F.Fab")
			(hide yes)
			(effects
				(font
					(size 1 1)
					(thickness 0.15)
				)
			)
		)
		(property "Voltage" ""
			(at -42.186 294.176 0)
			(layer "F.Fab")
			(hide yes)
			(effects
				(font
					(size 1 1)
					(thickness 0.15)
				)
			)
		)
		(sheetname "/PCIe-connector/")
		(sheetfile "pcie-conn.kicad_sch")
		(attr smd)
		(fp_rect
			(start -0.925 -0.47)
			(end 0.925 0.47)
			(stroke
				(width 0.05)
				(type default)
			)
			(fill no)
			(layer "F.CrtYd")
		)
		(fp_line
			(start -0.494 0.248)
			(end -0.494 -0.25)
			(stroke
				(width 0.15)
				(type solid)
			)
			(layer "F.Fab")
		)
		(fp_line
			(start 0.504 0.248)
			(end -0.494 0.248)
			(stroke
				(width 0.15)
				(type solid)
			)
			(layer "F.Fab")
		)
		(fp_line
			(start -0.494 -0.25)
			(end 0.504 -0.25)
			(stroke
				(width 0.15)
				(type solid)
			)
			(layer "F.Fab")
		)
		(fp_line
			(start 0.504 -0.25)
			(end 0.504 0.248)
			(stroke
				(width 0.15)
				(type solid)
			)
			(layer "F.Fab")
		)
		(pad "1" smd roundrect
			(at -0.48 0 270)
			(size 0.59 0.64)
			(layers "F.Cu" "F.Mask" "F.Paste")
			(roundrect_rratio 0.25)
			(net 370 "/PCIe-connector/PCIE_HPM_TX1_C_P")
			(pintype "passive")
		)
		(pad "2" smd roundrect
			(at 0.48 0 270)
			(size 0.59 0.64)
			(layers "F.Cu" "F.Mask" "F.Paste")
			(roundrect_rratio 0.25)
			(net 352 "PCIE_HPM_TX[1]_P")
			(pintype "passive")
		)
	)
	(footprint "antmicro-footprints:C_0402_1005Metric"
		(layer "F.Cu")
		(at 127.005 168.181 -90)
		(descr "Capacitor SMD 0402")
		(tags "capacitor SMD 0402")
		(property "Reference" "C30"
			(at 0.819 -0.404 90)
			(layer "F.SilkS")
			(effects
				(font
					(size 0.7 0.7)
					(thickness 0.15)
				)
				(justify right bottom)
			)
		)
		(property "Value" "C_100n_6V3_0402"
			(at 0 1.4 90)
			(layer "F.Fab")
			(effects
				(font
					(size 0.7 0.7)
					(thickness 0.15)
				)
				(justify right bottom)
			)
		)
		(property "Datasheet" "https://www.passivecomponent.com/wp-content/uploads/datasheet/WTC_MLCC_General_Purpose.pdf"
			(at 0 0 270)
			(layer "F.Fab")
			(hide yes)
			(effects
				(font
					(size 1.27 1.27)
					(thickness 0.15)
				)
			)
		)
		(property "Description" "SMT Multilayer Ceramic Capacitor, 0.1 µF, 6.3 V, 0402 [1005 Metric], ± 10%, X5R, Walsin MLCC"
			(at 0 0 270)
			(layer "F.Fab")
			(hide yes)
			(effects
				(font
					(size 1.27 1.27)
					(thickness 0.15)
				)
			)
		)
		(property "Author" "Antmicro"
			(at -41.176 295.186 0)
			(layer "F.Fab")
			(hide yes)
			(effects
				(font
					(size 1 1)
					(thickness 0.15)
				)
			)
		)
		(property "Dielectric" ""
			(at -41.176 295.186 0)
			(layer "F.Fab")
			(hide yes)
			(effects
				(font
					(size 1 1)
					(thickness 0.15)
				)
			)
		)
		(property "License" "Apache-2.0"
			(at -41.176 295.186 0)
			(layer "F.Fab")
			(hide yes)
			(effects
				(font
					(size 1 1)
					(thickness 0.15)
				)
			)
		)
		(property "MPN" "0402X104K6R3CT"
			(at -41.176 295.186 0)
			(layer "F.Fab")
			(hide yes)
			(effects
				(font
					(size 1 1)
					(thickness 0.15)
				)
			)
		)
		(property "Manufacturer" "Walsin"
			(at -41.176 295.186 0)
			(layer "F.Fab")
			(hide yes)
			(effects
				(font
					(size 1 1)
					(thickness 0.15)
				)
			)
		)
		(property "Public" "False"
			(at -41.176 295.186 0)
			(layer "F.Fab")
			(hide yes)
			(effects
				(font
					(size 1 1)
					(thickness 0.15)
				)
			)
		)
		(property "Val" "100n"
			(at -41.176 295.186 0)
			(layer "F.Fab")
			(hide yes)
			(effects
				(font
					(size 1 1)
					(thickness 0.15)
				)
			)
		)
		(property "Voltage" ""
			(at -41.176 295.186 0)
			(layer "F.Fab")
			(hide yes)
			(effects
				(font
					(size 1 1)
					(thickness 0.15)
				)
			)
		)
		(sheetname "/PCIe-connector/")
		(sheetfile "pcie-conn.kicad_sch")
		(attr smd)
		(fp_rect
			(start -0.925 -0.47)
			(end 0.925 0.47)
			(stroke
				(width 0.05)
				(type default)
			)
			(fill no)
			(layer "F.CrtYd")
		)
		(fp_line
			(start -0.494 0.248)
			(end -0.494 -0.25)
			(stroke
				(width 0.15)
				(type solid)
			)
			(layer "F.Fab")
		)
		(fp_line
			(start 0.504 0.248)
			(end -0.494 0.248)
			(stroke
				(width 0.15)
				(type solid)
			)
			(layer "F.Fab")
		)
		(fp_line
			(start -0.494 -0.25)
			(end 0.504 -0.25)
			(stroke
				(width 0.15)
				(type solid)
			)
			(layer "F.Fab")
		)
		(fp_line
			(start 0.504 -0.25)
			(end 0.504 0.248)
			(stroke
				(width 0.15)
				(type solid)
			)
			(layer "F.Fab")
		)
		(pad "1" smd roundrect
			(at -0.48 0 270)
			(size 0.59 0.64)
			(layers "F.Cu" "F.Mask" "F.Paste")
			(roundrect_rratio 0.25)
			(net 372 "/PCIe-connector/PCIE_HPM_TX1_C_N")
			(pintype "passive")
		)
		(pad "2" smd roundrect
			(at 0.48 0 270)
			(size 0.59 0.64)
			(layers "F.Cu" "F.Mask" "F.Paste")
			(roundrect_rratio 0.25)
			(net 354 "PCIE_HPM_TX[1]_N")
			(pintype "passive")
		)
	)
	(footprint "antmicro-footprints:C_0402_1005Metric"
		(layer "F.Cu")
		(at 134.77 154.48 -90)
		(descr "Capacitor SMD 0402")
		(tags "capacitor SMD 0402")
		(property "Reference" "C32"
			(at -2.98 -0.33 90)
			(layer "F.SilkS")
			(effects
				(font
					(size 0.7 0.7)
					(thickness 0.15)
				)
				(justify right bottom)
			)
		)
		(property "Value" "C_10u_0402"
			(at 0 1.4 90)
			(layer "F.Fab")
			(effects
				(font
					(size 0.7 0.7)
					(thickness 0.15)
				)
				(justify right bottom)
			)
		)
		(property "Datasheet" "https://www.yageo.com/en/Chart/Download/pdf/CC0402MRX5R5BB106"
			(at 0 0 270)
			(layer "F.Fab")
			(hide yes)
			(effects
				(font
					(size 1.27 1.27)
					(thickness 0.15)
				)
			)
		)
		(property "Description" "SMD Multilayer Ceramic Capacitor, 10 µF, 6.3 V, 0402 [1005 Metric], ± 20%, X5R, CC Series"
			(at 0 0 270)
			(layer "F.Fab")
			(hide yes)
			(effects
				(font
					(size 1.27 1.27)
					(thickness 0.15)
				)
			)
		)
		(property "Author" "Antmicro"
			(at -19.71 289.25 0)
			(layer "F.Fab")
			(hide yes)
			(effects
				(font
					(size 1 1)
					(thickness 0.15)
				)
			)
		)
		(property "Dielectric" ""
			(at -19.71 289.25 0)
			(layer "F.Fab")
			(hide yes)
			(effects
				(font
					(size 1 1)
					(thickness 0.15)
				)
			)
		)
		(property "License" "Apache-2.0"
			(at -19.71 289.25 0)
			(layer "F.Fab")
			(hide yes)
			(effects
				(font
					(size 1 1)
					(thickness 0.15)
				)
			)
		)
		(property "MPN" "CC0402MRX5R5BB106"
			(at -19.71 289.25 0)
			(layer "F.Fab")
			(hide yes)
			(effects
				(font
					(size 1 1)
					(thickness 0.15)
				)
			)
		)
		(property "Manufacturer" "YAGEO"
			(at -19.71 289.25 0)
			(layer "F.Fab")
			(hide yes)
			(effects
				(font
					(size 1 1)
					(thickness 0.15)
				)
			)
		)
		(property "Val" "10u"
			(at -19.71 289.25 0)
			(layer "F.Fab")
			(hide yes)
			(effects
				(font
					(size 1 1)
					(thickness 0.15)
				)
			)
		)
		(property "Voltage" ""
			(at -19.71 289.25 0)
			(layer "F.Fab")
			(hide yes)
			(effects
				(font
					(size 1 1)
					(thickness 0.15)
				)
			)
		)
		(sheetname "/PCIe-connector/")
		(sheetfile "pcie-conn.kicad_sch")
		(attr smd)
		(fp_rect
			(start -0.925 -0.47)
			(end 0.925 0.47)
			(stroke
				(width 0.05)
				(type default)
			)
			(fill no)
			(layer "F.CrtYd")
		)
		(fp_line
			(start -0.494 0.248)
			(end -0.494 -0.25)
			(stroke
				(width 0.15)
				(type solid)
			)
			(layer "F.Fab")
		)
		(fp_line
			(start 0.504 0.248)
			(end -0.494 0.248)
			(stroke
				(width 0.15)
				(type solid)
			)
			(layer "F.Fab")
		)
		(fp_line
			(start -0.494 -0.25)
			(end 0.504 -0.25)
			(stroke
				(width 0.15)
				(type solid)
			)
			(layer "F.Fab")
		)
		(fp_line
			(start 0.504 -0.25)
			(end 0.504 0.248)
			(stroke
				(width 0.15)
				(type solid)
			)
			(layer "F.Fab")
		)
		(pad "1" smd roundrect
			(at -0.48 0 270)
			(size 0.59 0.64)
			(layers "F.Cu" "F.Mask" "F.Paste")
			(roundrect_rratio 0.25)
			(net 1 "GND")
			(pintype "passive")
		)
		(pad "2" smd roundrect
			(at 0.48 0 270)
			(size 0.59 0.64)
			(layers "F.Cu" "F.Mask" "F.Paste")
			(roundrect_rratio 0.25)
			(net 2 "VCC3V3")
			(pintype "passive")
		)
	)
	(footprint "antmicro-footprints:C_0402_1005Metric"
		(layer "F.Cu")
		(at 117.475 154.575 -90)
		(descr "Capacitor SMD 0402")
		(tags "capacitor SMD 0402")
		(property "Reference" "C33"
			(at -2.975 -0.325 90)
			(layer "F.SilkS")
			(effects
				(font
					(size 0.7 0.7)
					(thickness 0.15)
				)
				(justify right bottom)
			)
		)
		(property "Value" "C_10u_0402"
			(at 0 1.4 90)
			(layer "F.Fab")
			(effects
				(font
					(size 0.7 0.7)
					(thickness 0.15)
				)
				(justify right bottom)
			)
		)
		(property "Datasheet" "https://www.yageo.com/en/Chart/Download/pdf/CC0402MRX5R5BB106"
			(at 0 0 270)
			(layer "F.Fab")
			(hide yes)
			(effects
				(font
					(size 1.27 1.27)
					(thickness 0.15)
				)
			)
		)
		(property "Description" "SMD Multilayer Ceramic Capacitor, 10 µF, 6.3 V, 0402 [1005 Metric], ± 20%, X5R, CC Series"
			(at 0 0 270)
			(layer "F.Fab")
			(hide yes)
			(effects
				(font
					(size 1.27 1.27)
					(thickness 0.15)
				)
			)
		)
		(property "Author" "Antmicro"
			(at -37.1 272.05 0)
			(layer "F.Fab")
			(hide yes)
			(effects
				(font
					(size 1 1)
					(thickness 0.15)
				)
			)
		)
		(property "Dielectric" ""
			(at -37.1 272.05 0)
			(layer "F.Fab")
			(hide yes)
			(effects
				(font
					(size 1 1)
					(thickness 0.15)
				)
			)
		)
		(property "License" "Apache-2.0"
			(at -37.1 272.05 0)
			(layer "F.Fab")
			(hide yes)
			(effects
				(font
					(size 1 1)
					(thickness 0.15)
				)
			)
		)
		(property "MPN" "CC0402MRX5R5BB106"
			(at -37.1 272.05 0)
			(layer "F.Fab")
			(hide yes)
			(effects
				(font
					(size 1 1)
					(thickness 0.15)
				)
			)
		)
		(property "Manufacturer" "YAGEO"
			(at -37.1 272.05 0)
			(layer "F.Fab")
			(hide yes)
			(effects
				(font
					(size 1 1)
					(thickness 0.15)
				)
			)
		)
		(property "Val" "10u"
			(at -37.1 272.05 0)
			(layer "F.Fab")
			(hide yes)
			(effects
				(font
					(size 1 1)
					(thickness 0.15)
				)
			)
		)
		(property "Voltage" ""
			(at -37.1 272.05 0)
			(layer "F.Fab")
			(hide yes)
			(effects
				(font
					(size 1 1)
					(thickness 0.15)
				)
			)
		)
		(sheetname "/PCIe-connector/")
		(sheetfile "pcie-conn.kicad_sch")
		(attr smd)
		(fp_rect
			(start -0.925 -0.47)
			(end 0.925 0.47)
			(stroke
				(width 0.05)
				(type default)
			)
			(fill no)
			(layer "F.CrtYd")
		)
		(fp_line
			(start -0.494 0.248)
			(end -0.494 -0.25)
			(stroke
				(width 0.15)
				(type solid)
			)
			(layer "F.Fab")
		)
		(fp_line
			(start 0.504 0.248)
			(end -0.494 0.248)
			(stroke
				(width 0.15)
				(type solid)
			)
			(layer "F.Fab")
		)
		(fp_line
			(start -0.494 -0.25)
			(end 0.504 -0.25)
			(stroke
				(width 0.15)
				(type solid)
			)
			(layer "F.Fab")
		)
		(fp_line
			(start 0.504 -0.25)
			(end 0.504 0.248)
			(stroke
				(width 0.15)
				(type solid)
			)
			(layer "F.Fab")
		)
		(pad "1" smd roundrect
			(at -0.48 0 270)
			(size 0.59 0.64)
			(layers "F.Cu" "F.Mask" "F.Paste")
			(roundrect_rratio 0.25)
			(net 1 "GND")
			(pintype "passive")
		)
		(pad "2" smd roundrect
			(at 0.48 0 270)
			(size 0.59 0.64)
			(layers "F.Cu" "F.Mask" "F.Paste")
			(roundrect_rratio 0.25)
			(net 2 "VCC3V3")
			(pintype "passive")
		)
	)
)
